# BASEBOARD_FAB2 (Tioga Pass) — schematic netlist excerpt (pin names and nets, part order shuffled) for the footprints in the layout excerpt that follows; sources: Cadence DE-HDL packaged netlist, KiCad conversion of Wiwynn_Tioga_Pass_MB.brd

U6W12  NC7SB3157  IC  pkg SMLF  page 176
  B1  = SPA_MID_DBG2_RX_BUF
  GND  = GND
  B0  = SPA_MID_DBG1_RX
  A  = SPA_MID_DBG_RX
  VCC  = P3V3_STBY
  S  = DEBUG_CARD2_PRSNT

C4B1  SC22U16V5MX-4-GP  20%  pkg SMD-BCG5  page 234 : \1\ = VR_FET_SW_P12V_STBY_PVPP_KLM ; \2\ = GND
FB4A1  FERRITE  22 1% FB  pkg SM  page 234 : A = P12V_STBY ; B = VR_FET_SW_P12V_STBY_PVPP_KLM
C3D12  CAP_A  22.0UF 4V 20% X6S  pkg 0603V  page 76 : A = PVCCMCP_CPU1 ; B = GND

(kicad_pcb
	(version 20260206)
	(generator "pcbnew")
	(generator_version "10.0")
	(general
		(thickness 1.6)
		(legacy_teardrops no)
	)
	(paper "A4")
	(title_block
		(title "Wiwynn_Tioga_Pass_MB.brd")
		(comment 1 "Tioga Pass / footprints 385-388 of 4770")
	)
	(layers
		(0 "F.Cu" signal "TOP")
		(4 "In1.Cu" signal "L2GND")
		(6 "In2.Cu" signal "L3")
		(8 "In3.Cu" signal "L4GND")
		(10 "In4.Cu" signal "L5")
		(12 "In5.Cu" signal "L6GND")
		(14 "In6.Cu" signal "L7VCC")
		(16 "In7.Cu" signal "L8VCC")
		(18 "In8.Cu" signal "L9GND")
		(20 "In9.Cu" signal "L10")
		(22 "In10.Cu" signal "L11GND")
		(24 "In11.Cu" signal "L12")
		(26 "In12.Cu" signal "L13GND")
		(2 "B.Cu" signal "BOTTOM")
		(9 "F.Adhes" user "F.Adhesive")
		(11 "B.Adhes" user "B.Adhesive")
		(13 "F.Paste" user "Package Geometry/Pastemask Top")
		(15 "B.Paste" user "Package Geometry/Pastemask Bottom")
		(5 "F.SilkS" user "Ref Des/Silkscreen Top")
		(7 "B.SilkS" user "Ref Des/Silkscreen Bottom")
		(1 "F.Mask" user "Board Geometry/Soldermask Top")
		(3 "B.Mask" user "Board Geometry/Soldermask Bottom")
		(17 "Dwgs.User" user "User.Drawings")
		(19 "Cmts.User" user "User.Comments")
		(21 "Eco1.User" user "User.Eco1")
		(23 "Eco2.User" user "User.Eco2")
		(25 "Edge.Cuts" user "Board Geometry/Outline")
		(27 "Margin" user)
		(31 "F.CrtYd" user "Package Geometry/Place Bound Top")
		(29 "B.CrtYd" user "Package Geometry/Place Bound Bottom")
		(35 "F.Fab" user "Ref Des/Assembly Top")
		(33 "B.Fab" user "Ref Des/Assembly Bottom")
	)
	(footprint ""
		(layer "F.Cu")
		(at 483.616 -139.4206)
		(property "Reference" "U6W12"
			(at 0 -1.2065 0)
			(unlocked yes)
			(layer "F.SilkS")
			(effects
				(font
					(size 1.27 0.9652)
					(thickness 0.1524)
				)
				(justify left)
			)
		)
		(property "Value" ""
			(at 0 0 0)
			(layer "F.Fab")
			(effects
				(font
					(size 1.27 1.27)
				)
			)
		)
		(duplicate_pad_numbers_are_jumpers no)
		(fp_circle
			(center -0.848614 -0.6477)
			(end -0.721614 -0.6477)
			(stroke
				(width 0.254)
				(type default)
			)
			(fill no)
			(layer "F.SilkS")
		)
		(fp_poly
			(pts
				(xy 0.21463 -0.450088) (xy 1.56337 -0.450088) (xy 1.56337 1.75006) (xy 0.21463 1.75006)
			)
			(stroke
				(width 0)
				(type default)
			)
			(fill no)
			(layer "F.CrtYd")
		)
		(fp_line
			(start 0.21463 -0.450088)
			(end 1.56337 -0.450088)
			(stroke
				(width 0.1)
				(type default)
			)
			(layer "F.Fab")
		)
		(fp_line
			(start 0.21463 1.75006)
			(end 0.21463 -0.450088)
			(stroke
				(width 0.1)
				(type default)
			)
			(layer "F.Fab")
		)
		(fp_line
			(start 1.56337 -0.450088)
			(end 1.56337 1.75006)
			(stroke
				(width 0.1)
				(type default)
			)
			(layer "F.Fab")
		)
		(fp_line
			(start 1.56337 1.75006)
			(end 0.21463 1.75006)
			(stroke
				(width 0.1)
				(type default)
			)
			(layer "F.Fab")
		)
		(fp_circle
			(center -0.848614 -0.6477)
			(end -0.721614 -0.6477)
			(stroke
				(width 0.254)
				(type default)
			)
			(fill no)
			(layer "F.Fab")
		)
		(pad "1" smd rect
			(at 0 0)
			(size 1.016 0.381)
			(layers "F.Cu" "F.Mask" "F.Paste")
			(net "SPA_MID_DBG2_RX_BUF")
		)
		(pad "2" smd rect
			(at 0 0.649986)
			(size 1.016 0.381)
			(layers "F.Cu" "F.Mask" "F.Paste")
			(net "GND")
		)
		(pad "3" smd rect
			(at 0 1.299972)
			(size 1.016 0.381)
			(layers "F.Cu" "F.Mask" "F.Paste")
			(net "SPA_MID_DBG1_RX")
		)
		(pad "4" smd rect
			(at 1.778 1.299972)
			(size 1.016 0.381)
			(layers "F.Cu" "F.Mask" "F.Paste")
			(net "SPA_MID_DBG_RX")
		)
		(pad "5" smd rect
			(at 1.778 0.649986)
			(size 1.016 0.381)
			(layers "F.Cu" "F.Mask" "F.Paste")
			(net "P3V3_STBY")
		)
		(pad "6" smd rect
			(at 1.778 0)
			(size 1.016 0.381)
			(layers "F.Cu" "F.Mask" "F.Paste")
			(net "DEBUG_CARD2_PRSNT")
		)
	)
	(footprint ""
		(layer "F.Cu")
		(at 185.3184 -138.2141)
		(property "Reference" "FB4A1"
			(at 0 0 0)
			(layer "F.SilkS")
			(hide yes)
			(effects
				(font
					(size 1.27 1.27)
				)
			)
		)
		(property "Value" ""
			(at 0 0 0)
			(layer "F.Fab")
			(effects
				(font
					(size 1.27 1.27)
				)
			)
		)
		(duplicate_pad_numbers_are_jumpers no)
		(fp_poly
			(pts
				(xy -0.7239 -0.26035) (xy 0.7239 -0.26035) (xy 0.7239 2.03835) (xy -0.7239 2.03835)
			)
			(stroke
				(width 0)
				(type default)
			)
			(fill no)
			(layer "F.CrtYd")
		)
		(fp_line
			(start -0.7239 -0.26035)
			(end 0.7239 -0.26035)
			(stroke
				(width 0.1)
				(type default)
			)
			(layer "F.Fab")
		)
		(fp_line
			(start -0.7239 2.03835)
			(end -0.7239 -0.26035)
			(stroke
				(width 0.1)
				(type default)
			)
			(layer "F.Fab")
		)
		(fp_line
			(start 0.7239 -0.26035)
			(end 0.7239 2.03835)
			(stroke
				(width 0.1)
				(type default)
			)
			(layer "F.Fab")
		)
		(fp_line
			(start 0.7239 2.03835)
			(end -0.7239 2.03835)
			(stroke
				(width 0.1)
				(type default)
			)
			(layer "F.Fab")
		)
		(pad "1" smd rect
			(at 0 0)
			(size 1.27 1.016)
			(layers "F.Cu" "F.Mask" "F.Paste")
			(net "P12V_STBY")
		)
		(pad "2" smd rect
			(at 0 1.778)
			(size 1.27 1.016)
			(layers "F.Cu" "F.Mask" "F.Paste")
			(net "VR_FET_SW_P12V_STBY_PVPP_KLM")
		)
		(zone
			(layer "F.Cu")
			(hatch none 0.5)
			(connect_pads
				(clearance 0)
			)
			(min_thickness 0.25)
			(keepout
				(tracks not_allowed)
				(vias allowed)
				(pads allowed)
				(copperpour not_allowed)
				(footprints allowed)
			)
			(placement
				(enabled no)
				(sheetname "")
			)
			(fill
				(thermal_gap 0.5)
				(thermal_bridge_width 0.5)
				(island_removal_mode 0)
			)
			(polygon
				(pts
					(xy 185.9534 -137.7061) (xy 185.9534 -136.9441) (xy 185.8645 -136.9441) (xy 184.6834 -136.9441)
					(xy 184.6834 -137.7061)
				)
			)
		)
	)
	(footprint ""
		(layer "F.Cu")
		(at 109.638592 -77.429614)
		(property "Reference" "C3D12"
			(at 0 0 0)
			(layer "F.SilkS")
			(hide yes)
			(effects
				(font
					(size 1.27 1.27)
				)
			)
		)
		(property "Value" ""
			(at 0 0 0)
			(layer "F.Fab")
			(effects
				(font
					(size 1.27 1.27)
				)
			)
		)
		(duplicate_pad_numbers_are_jumpers no)
		(fp_poly
			(pts
				(xy -0.4953 -0.2032) (xy 0.4953 -0.2032) (xy 0.4953 1.6002) (xy -0.4953 1.6002)
			)
			(stroke
				(width 0)
				(type default)
			)
			(fill no)
			(layer "F.CrtYd")
		)
		(fp_line
			(start -0.4953 -0.2032)
			(end 0.4953 -0.2032)
			(stroke
				(width 0.1)
				(type default)
			)
			(layer "F.Fab")
		)
		(fp_line
			(start -0.4953 1.6002)
			(end -0.4953 -0.2032)
			(stroke
				(width 0.1)
				(type default)
			)
			(layer "F.Fab")
		)
		(fp_line
			(start 0.4953 -0.2032)
			(end 0.4953 1.6002)
			(stroke
				(width 0.1)
				(type default)
			)
			(layer "F.Fab")
		)
		(fp_line
			(start 0.4953 1.6002)
			(end -0.4953 1.6002)
			(stroke
				(width 0.1)
				(type default)
			)
			(layer "F.Fab")
		)
		(pad "1" smd rect
			(at 0 0)
			(size 0.762 0.889)
			(layers "F.Cu" "F.Mask" "F.Paste")
			(net "PVCCMCP_CPU1")
		)
		(pad "2" smd rect
			(at 0 1.397)
			(size 0.762 0.889)
			(layers "F.Cu" "F.Mask" "F.Paste")
			(net "GND")
		)
		(zone
			(layer "F.Cu")
			(hatch none 0.5)
			(connect_pads
				(clearance 0)
			)
			(min_thickness 0.25)
			(keepout
				(tracks not_allowed)
				(vias allowed)
				(pads allowed)
				(copperpour not_allowed)
				(footprints allowed)
			)
			(placement
				(enabled no)
				(sheetname "")
			)
			(fill
				(thermal_gap 0.5)
				(thermal_bridge_width 0.5)
				(island_removal_mode 0)
			)
			(polygon
				(pts
					(xy 109.257592 -76.985114) (xy 110.019592 -76.985114) (xy 110.019592 -76.477114) (xy 109.257592 -76.477114)
				)
			)
		)
	)
	(footprint ""
		(layer "F.Cu")
		(at 184.147968 -134.173722 90)
		(property "Reference" "C4B1"
			(at 0 0 90)
			(layer "F.SilkS")
			(hide yes)
			(effects
				(font
					(size 1.27 1.27)
				)
			)
		)
		(property "Value" "*"
			(at -0.0762 -6.2357 90)
			(unlocked yes)
			(layer "F.Fab")
			(hide yes)
			(effects
				(font
					(size 1.27 1.016)
					(thickness 0.1524)
				)
			)
		)
		(property "Device Type" "SC22U16V5MX-4-GP_SMD-BCG5-SC22A"
			(at -0.0762 -8.2677 90)
			(unlocked yes)
			(layer "F.Fab")
			(hide yes)
			(effects
				(font
					(size 1.27 1.016)
					(thickness 0.1524)
				)
			)
		)
		(duplicate_pad_numbers_are_jumpers no)
		(fp_line
			(start 0.635 0)
			(end -0.635 0)
			(stroke
				(width 0.508)
				(type default)
			)
			(layer "F.SilkS")
		)
		(fp_rect
			(start -0.9652 1.778)
			(end 0.9652 -1.778)
			(stroke
				(width 0)
				(type default)
			)
			(fill no)
			(layer "F.CrtYd")
		)
		(fp_poly
			(pts
				(xy -0.9652 -1.778) (xy 0.9652 -1.778) (xy 0.9652 1.778) (xy -0.9652 1.778)
			)
			(stroke
				(width 0)
				(type default)
			)
			(fill no)
			(layer "F.Fab")
		)
		(pad "1" smd rect
			(at 0 -0.9652 90)
			(size 1.397 1.143)
			(layers "F.Cu" "F.Mask" "F.Paste")
			(net "VR_FET_SW_P12V_STBY_PVPP_KLM")
		)
		(pad "2" smd rect
			(at 0 0.9652 90)
			(size 1.397 1.143)
			(layers "F.Cu" "F.Mask" "F.Paste")
			(net "GND")
		)
	)
)
